# T6G (Grand Teton) — schematic netlist excerpt (pin names and nets, part order shuffled) for the footprints in the layout excerpt that follows; sources: Cadence DE-HDL packaged netlist, KiCad conversion of 04192023_DAF0TMB3IC0_F0TG_MB_C_brd_V02_OCP.brd

PC392  Q_CAP  0.1UF 25V 10% X7R  pkg 0402  page 218 : A = PVDDCR_CPU1_P1 ; B = GND

Q146  MOSFET_NCH_DUAL  PJT138K IC  pkg SOT363XD  page 125
  S1  = GND
  G1  = SWB_HSC_PWRGD
  D2  = SWB_HSC_PWRGD_ISO
  S2  = GND
  G2  = SWB_HSC_PWRGD_N
  D1  = SWB_HSC_PWRGD_N

PC2082  Q_CAP  10UF 16V 10% X6S  pkg C0805  page 134 : A = P12V_OCP_SFF ; B = GND

(kicad_pcb
	(version 20260206)
	(generator "pcbnew")
	(generator_version "10.0")
	(general
		(thickness 1.6)
		(legacy_teardrops no)
	)
	(paper "A4")
	(title_block
		(title "04192023_DAF0TMB3IC0_F0TG_MB_C_brd_V02_OCP.brd")
		(comment 1 "Grand Teton / footprints 3687-3689 of 8354")
	)
	(layers
		(0 "F.Cu" signal "TOP")
		(4 "In1.Cu" signal "GND")
		(6 "In2.Cu" signal "IN1")
		(8 "In3.Cu" signal "GND1")
		(10 "In4.Cu" signal "IN2")
		(12 "In5.Cu" signal "GND2")
		(14 "In6.Cu" signal "IN3")
		(16 "In7.Cu" signal "GND3")
		(18 "In8.Cu" signal "VCC")
		(20 "In9.Cu" signal "VCC1")
		(22 "In10.Cu" signal "GND4")
		(24 "In11.Cu" signal "IN4")
		(26 "In12.Cu" signal "GND5")
		(28 "In13.Cu" signal "IN5")
		(30 "In14.Cu" signal "GND6")
		(32 "In15.Cu" signal "IN6")
		(34 "In16.Cu" signal "GND7")
		(2 "B.Cu" signal "BOTTOM")
		(9 "F.Adhes" user "F.Adhesive")
		(11 "B.Adhes" user "B.Adhesive")
		(13 "F.Paste" user "Package Geometry/Pastemask Top")
		(15 "B.Paste" user "Package Geometry/Pastemask Bottom")
		(5 "F.SilkS" user "Ref Des/Silkscreen Top")
		(7 "B.SilkS" user "Ref Des/Silkscreen Bottom")
		(1 "F.Mask" user "Board Geometry/Soldermask Top")
		(3 "B.Mask" user "Board Geometry/Soldermask Bottom")
		(17 "Dwgs.User" user "User.Drawings")
		(19 "Cmts.User" user "User.Comments")
		(21 "Eco1.User" user "User.Eco1")
		(23 "Eco2.User" user "User.Eco2")
		(25 "Edge.Cuts" user "Board Geometry/Outline")
		(27 "Margin" user)
		(31 "F.CrtYd" user "Package Geometry/Place Bound Top")
		(29 "B.CrtYd" user "Package Geometry/Place Bound Bottom")
		(35 "F.Fab" user "Ref Des/Assembly Top")
		(33 "B.Fab" user "Ref Des/Assembly Bottom")
	)
	(footprint ""
		(layer "F.Cu")
		(at 445.552068 -23.64105)
		(property "Reference" "PC2082"
			(at 0 0 0)
			(layer "F.SilkS")
			(hide yes)
			(effects
				(font
					(size 1.27 1.27)
				)
			)
		)
		(property "Value" ""
			(at 0 0 0)
			(layer "F.Fab")
			(effects
				(font
					(size 1.27 1.27)
				)
			)
		)
		(duplicate_pad_numbers_are_jumpers no)
		(fp_line
			(start -1.524 -0.762)
			(end 1.524 -0.762)
			(stroke
				(width 0.1524)
				(type default)
			)
			(layer "F.SilkS")
		)
		(fp_line
			(start -1.524 0.762)
			(end -1.524 -0.762)
			(stroke
				(width 0.1524)
				(type default)
			)
			(layer "F.SilkS")
		)
		(fp_line
			(start 1.524 -0.762)
			(end 1.524 0.762)
			(stroke
				(width 0.1524)
				(type default)
			)
			(layer "F.SilkS")
		)
		(fp_line
			(start 1.524 0.762)
			(end -1.524 0.762)
			(stroke
				(width 0.1524)
				(type default)
			)
			(layer "F.SilkS")
		)
		(fp_line
			(start -1.1049 -0.724916)
			(end -1.1049 0.724916)
			(stroke
				(width 0.1)
				(type default)
			)
			(layer "F.Fab")
		)
		(fp_line
			(start -1.1049 0.724916)
			(end 1.1049 0.724916)
			(stroke
				(width 0.1)
				(type default)
			)
			(layer "F.Fab")
		)
		(fp_line
			(start 1.1049 -0.724916)
			(end -1.1049 -0.724916)
			(stroke
				(width 0.1)
				(type default)
			)
			(layer "F.Fab")
		)
		(fp_line
			(start 1.1049 0.724916)
			(end 1.1049 -0.724916)
			(stroke
				(width 0.1)
				(type default)
			)
			(layer "F.Fab")
		)
		(pad "1" smd rect
			(at -0.889 0 180)
			(size 1.016 1.27)
			(layers "F.Cu" "F.Mask" "F.Paste")
			(net "P12V_OCP_SFF")
		)
		(pad "2" smd rect
			(at 0.889 0 180)
			(size 1.016 1.27)
			(layers "F.Cu" "F.Mask" "F.Paste")
			(net "GND")
		)
	)
	(footprint ""
		(layer "F.Cu")
		(at 108.521754 -327.074276 90)
		(property "Reference" "PC392"
			(at 0 0 90)
			(layer "F.SilkS")
			(hide yes)
			(effects
				(font
					(size 1.27 1.27)
				)
			)
		)
		(property "Value" ""
			(at 0 0 90)
			(layer "F.Fab")
			(effects
				(font
					(size 1.27 1.27)
				)
			)
		)
		(duplicate_pad_numbers_are_jumpers no)
		(fp_line
			(start 0.7874 -0.4064)
			(end 0.7874 0.4064)
			(stroke
				(width 0.1524)
				(type default)
			)
			(layer "F.SilkS")
		)
		(fp_line
			(start -0.7874 -0.4064)
			(end 0.7874 -0.4064)
			(stroke
				(width 0.1524)
				(type default)
			)
			(layer "F.SilkS")
		)
		(fp_line
			(start 0.7874 0.4064)
			(end -0.7874 0.4064)
			(stroke
				(width 0.1524)
				(type default)
			)
			(layer "F.SilkS")
		)
		(fp_line
			(start -0.7874 0.4064)
			(end -0.7874 -0.4064)
			(stroke
				(width 0.1524)
				(type default)
			)
			(layer "F.SilkS")
		)
		(fp_line
			(start -0.12065 -0.305054)
			(end -0.12065 -0.2794)
			(stroke
				(width 0.1)
				(type default)
			)
			(layer "F.Fab")
		)
		(fp_line
			(start -0.67945 -0.305054)
			(end -0.12065 -0.305054)
			(stroke
				(width 0.1)
				(type default)
			)
			(layer "F.Fab")
		)
		(fp_line
			(start 0.67945 -0.3048)
			(end 0.67945 0.3048)
			(stroke
				(width 0.1)
				(type default)
			)
			(layer "F.Fab")
		)
		(fp_line
			(start 0.12065 -0.3048)
			(end 0.67945 -0.3048)
			(stroke
				(width 0.1)
				(type default)
			)
			(layer "F.Fab")
		)
		(fp_line
			(start 0.12065 -0.2794)
			(end 0.12065 -0.3048)
			(stroke
				(width 0.1)
				(type default)
			)
			(layer "F.Fab")
		)
		(fp_line
			(start -0.12065 -0.2794)
			(end 0.12065 -0.2794)
			(stroke
				(width 0.1)
				(type default)
			)
			(layer "F.Fab")
		)
		(fp_line
			(start 0.120396 0.2794)
			(end -0.12065 0.2794)
			(stroke
				(width 0.1)
				(type default)
			)
			(layer "F.Fab")
		)
		(fp_line
			(start -0.12065 0.2794)
			(end -0.12065 0.3048)
			(stroke
				(width 0.1)
				(type default)
			)
			(layer "F.Fab")
		)
		(fp_line
			(start 0.67945 0.3048)
			(end 0.120396 0.3048)
			(stroke
				(width 0.1)
				(type default)
			)
			(layer "F.Fab")
		)
		(fp_line
			(start 0.120396 0.3048)
			(end 0.120396 0.2794)
			(stroke
				(width 0.1)
				(type default)
			)
			(layer "F.Fab")
		)
		(fp_line
			(start -0.12065 0.3048)
			(end -0.67945 0.3048)
			(stroke
				(width 0.1)
				(type default)
			)
			(layer "F.Fab")
		)
		(fp_line
			(start -0.67945 0.3048)
			(end -0.67945 -0.305054)
			(stroke
				(width 0.1)
				(type default)
			)
			(layer "F.Fab")
		)
		(pad "1" smd circle
			(at -0.40005 0 90)
			(size 0 0)
			(layers "F.Cu" "F.Mask" "F.Paste")
			(net "PVDDCR_CPU1_P1")
		)
		(pad "2" smd circle
			(at 0.40005 0 90)
			(size 0 0)
			(layers "F.Cu" "F.Mask" "F.Paste")
			(net "GND")
		)
	)
	(footprint ""
		(layer "F.Cu")
		(at 352.135186 -428.406052 90)
		(property "Reference" "Q146"
			(at -1.2954 1.787652 90)
			(unlocked yes)
			(layer "F.SilkS")
			(effects
				(font
					(size 0.7874 0.5842)
					(thickness 0.1524)
				)
				(justify left)
			)
		)
		(property "Value" ""
			(at 0 0 90)
			(layer "F.Fab")
			(effects
				(font
					(size 1.27 1.27)
				)
			)
		)
		(duplicate_pad_numbers_are_jumpers no)
		(fp_line
			(start 1.332738 -1.100074)
			(end 1.332738 1.100074)
			(stroke
				(width 0.1524)
				(type default)
			)
			(layer "F.SilkS")
		)
		(fp_line
			(start 0.4826 -1.100074)
			(end 1.332738 -1.100074)
			(stroke
				(width 0.1524)
				(type default)
			)
			(layer "F.SilkS")
		)
		(fp_line
			(start -0.4826 -1.100074)
			(end 0 -0.541274)
			(stroke
				(width 0.1524)
				(type default)
			)
			(layer "F.SilkS")
		)
		(fp_line
			(start -1.332738 -1.100074)
			(end -0.4826 -1.100074)
			(stroke
				(width 0.1524)
				(type default)
			)
			(layer "F.SilkS")
		)
		(fp_line
			(start 0 -0.541274)
			(end 0.4826 -1.100074)
			(stroke
				(width 0.1524)
				(type default)
			)
			(layer "F.SilkS")
		)
		(fp_line
			(start 1.332738 1.100074)
			(end -1.332738 1.100074)
			(stroke
				(width 0.1524)
				(type default)
			)
			(layer "F.SilkS")
		)
		(fp_line
			(start -1.332738 1.100074)
			(end -1.332738 -1.100074)
			(stroke
				(width 0.1524)
				(type default)
			)
			(layer "F.SilkS")
		)
		(fp_poly
			(pts
				(xy -1.533144 -0.649986) (xy -2.2352 -0.298958) (xy -2.2352 -1.001014)
			)
			(stroke
				(width 0)
				(type default)
			)
			(fill yes)
			(layer "F.SilkS")
		)
		(fp_line
			(start 0.674878 -1.100074)
			(end 0.674878 1.100074)
			(stroke
				(width 0.1)
				(type default)
			)
			(layer "F.Fab")
		)
		(fp_line
			(start -0.674878 -1.100074)
			(end 0.674878 -1.100074)
			(stroke
				(width 0.1)
				(type default)
			)
			(layer "F.Fab")
		)
		(fp_line
			(start 0.674878 1.100074)
			(end -0.674878 1.100074)
			(stroke
				(width 0.1)
				(type default)
			)
			(layer "F.Fab")
		)
		(fp_line
			(start -0.674878 1.100074)
			(end -0.674878 -1.100074)
			(stroke
				(width 0.1)
				(type default)
			)
			(layer "F.Fab")
		)
		(fp_poly
			(pts
				(xy -2.2352 -0.298958) (xy -2.2352 -1.001014) (xy -1.533144 -0.649986)
			)
			(stroke
				(width 0)
				(type default)
			)
			(fill yes)
			(layer "F.Fab")
		)
		(pad "1" smd rect
			(at -0.94996 -0.649986 180)
			(size 0.4318 0.508)
			(layers "F.Cu" "F.Mask" "F.Paste")
			(net "GND")
		)
		(pad "2" smd rect
			(at -0.94996 0 180)
			(size 0.4318 0.508)
			(layers "F.Cu" "F.Mask" "F.Paste")
			(net "SWB_HSC_PWRGD")
		)
		(pad "3" smd rect
			(at -0.94996 0.649986 180)
			(size 0.4318 0.508)
			(layers "F.Cu" "F.Mask" "F.Paste")
			(net "SWB_HSC_PWRGD_ISO")
		)
		(pad "4" smd rect
			(at 0.94996 0.649986 180)
			(size 0.4318 0.508)
			(layers "F.Cu" "F.Mask" "F.Paste")
			(net "GND")
		)
		(pad "5" smd rect
			(at 0.94996 0 180)
			(size 0.4318 0.508)
			(layers "F.Cu" "F.Mask" "F.Paste")
			(net "SWB_HSC_PWRGD_N")
		)
		(pad "6" smd rect
			(at 0.94996 -0.649986 180)
			(size 0.4318 0.508)
			(layers "F.Cu" "F.Mask" "F.Paste")
			(net "SWB_HSC_PWRGD_N")
		)
	)
)
